# T6G (Grand Teton) — schematic netlist excerpt (pin names and nets, part order shuffled) for the footprints in the layout excerpt that follows; sources: Cadence DE-HDL packaged netlist, KiCad conversion of 04192023_DAF0TMB3IC0_F0TG_MB_C_brd_V02_OCP.brd

C75  Q_CAP  0.1UF 25V 10% X7R  pkg 0402  page 183 : A = P3V3_9ZXL045_P1_VDD ; B = GND
R801  Q_RES  0 5% CHIP  pkg 0201LF  page 185 : A = SMB_RT_CPU1_P0_ROM_MUX_2D_SDA ; B = SMB_RT_CPU1_P0_ROM_MUX_2D_R_SDA
R6502  Q_RES  2.2K 5% CHIP  pkg 0402LF  page 28 : A = CPU0_FORCE_SELFREFRESH ; B = GND

(kicad_pcb
	(version 20260206)
	(generator "pcbnew")
	(generator_version "10.0")
	(general
		(thickness 1.6)
		(legacy_teardrops no)
	)
	(paper "A4")
	(title_block
		(title "04192023_DAF0TMB3IC0_F0TG_MB_C_brd_V02_OCP.brd")
		(comment 1 "Grand Teton / footprints 5420-5422 of 8354")
	)
	(layers
		(0 "F.Cu" signal "TOP")
		(4 "In1.Cu" signal "GND")
		(6 "In2.Cu" signal "IN1")
		(8 "In3.Cu" signal "GND1")
		(10 "In4.Cu" signal "IN2")
		(12 "In5.Cu" signal "GND2")
		(14 "In6.Cu" signal "IN3")
		(16 "In7.Cu" signal "GND3")
		(18 "In8.Cu" signal "VCC")
		(20 "In9.Cu" signal "VCC1")
		(22 "In10.Cu" signal "GND4")
		(24 "In11.Cu" signal "IN4")
		(26 "In12.Cu" signal "GND5")
		(28 "In13.Cu" signal "IN5")
		(30 "In14.Cu" signal "GND6")
		(32 "In15.Cu" signal "IN6")
		(34 "In16.Cu" signal "GND7")
		(2 "B.Cu" signal "BOTTOM")
		(9 "F.Adhes" user "F.Adhesive")
		(11 "B.Adhes" user "B.Adhesive")
		(13 "F.Paste" user "Package Geometry/Pastemask Top")
		(15 "B.Paste" user "Package Geometry/Pastemask Bottom")
		(5 "F.SilkS" user "Ref Des/Silkscreen Top")
		(7 "B.SilkS" user "Ref Des/Silkscreen Bottom")
		(1 "F.Mask" user "Board Geometry/Soldermask Top")
		(3 "B.Mask" user "Board Geometry/Soldermask Bottom")
		(17 "Dwgs.User" user "User.Drawings")
		(19 "Cmts.User" user "User.Comments")
		(21 "Eco1.User" user "User.Eco1")
		(23 "Eco2.User" user "User.Eco2")
		(25 "Edge.Cuts" user "Board Geometry/Outline")
		(27 "Margin" user)
		(31 "F.CrtYd" user "Package Geometry/Place Bound Top")
		(29 "B.CrtYd" user "Package Geometry/Place Bound Bottom")
		(35 "F.Fab" user "Ref Des/Assembly Top")
		(33 "B.Fab" user "Ref Des/Assembly Bottom")
	)
	(footprint ""
		(layer "B.Cu")
		(at 108.15828 -410.252672)
		(property "Reference" "C75"
			(at 0 0 0)
			(layer "B.SilkS")
			(hide yes)
			(effects
				(font
					(size 1.27 1.27)
				)
				(justify mirror)
			)
		)
		(property "Value" ""
			(at 0 0 0)
			(layer "B.Fab")
			(effects
				(font
					(size 1.27 1.27)
				)
				(justify mirror)
			)
		)
		(duplicate_pad_numbers_are_jumpers no)
		(fp_line
			(start -0.7874 -0.4064)
			(end -0.7874 0.4064)
			(stroke
				(width 0.1524)
				(type default)
			)
			(layer "B.SilkS")
		)
		(fp_line
			(start -0.7874 0.4064)
			(end 0.7874 0.4064)
			(stroke
				(width 0.1524)
				(type default)
			)
			(layer "B.SilkS")
		)
		(fp_line
			(start 0.7874 -0.4064)
			(end -0.7874 -0.4064)
			(stroke
				(width 0.1524)
				(type default)
			)
			(layer "B.SilkS")
		)
		(fp_line
			(start 0.7874 0.4064)
			(end 0.7874 -0.4064)
			(stroke
				(width 0.1524)
				(type default)
			)
			(layer "B.SilkS")
		)
		(fp_line
			(start -0.67945 -0.3048)
			(end -0.67945 0.3048)
			(stroke
				(width 0.1)
				(type default)
			)
			(layer "B.Fab")
		)
		(fp_line
			(start -0.67945 0.3048)
			(end -0.120396 0.3048)
			(stroke
				(width 0.1)
				(type default)
			)
			(layer "B.Fab")
		)
		(fp_line
			(start -0.12065 -0.3048)
			(end -0.67945 -0.3048)
			(stroke
				(width 0.1)
				(type default)
			)
			(layer "B.Fab")
		)
		(fp_line
			(start -0.12065 -0.2794)
			(end -0.12065 -0.3048)
			(stroke
				(width 0.1)
				(type default)
			)
			(layer "B.Fab")
		)
		(fp_line
			(start -0.120396 0.2794)
			(end 0.12065 0.2794)
			(stroke
				(width 0.1)
				(type default)
			)
			(layer "B.Fab")
		)
		(fp_line
			(start -0.120396 0.3048)
			(end -0.120396 0.2794)
			(stroke
				(width 0.1)
				(type default)
			)
			(layer "B.Fab")
		)
		(fp_line
			(start 0.12065 -0.305054)
			(end 0.12065 -0.2794)
			(stroke
				(width 0.1)
				(type default)
			)
			(layer "B.Fab")
		)
		(fp_line
			(start 0.12065 -0.2794)
			(end -0.12065 -0.2794)
			(stroke
				(width 0.1)
				(type default)
			)
			(layer "B.Fab")
		)
		(fp_line
			(start 0.12065 0.2794)
			(end 0.12065 0.3048)
			(stroke
				(width 0.1)
				(type default)
			)
			(layer "B.Fab")
		)
		(fp_line
			(start 0.12065 0.3048)
			(end 0.67945 0.3048)
			(stroke
				(width 0.1)
				(type default)
			)
			(layer "B.Fab")
		)
		(fp_line
			(start 0.67945 -0.305054)
			(end 0.12065 -0.305054)
			(stroke
				(width 0.1)
				(type default)
			)
			(layer "B.Fab")
		)
		(fp_line
			(start 0.67945 0.3048)
			(end 0.67945 -0.305054)
			(stroke
				(width 0.1)
				(type default)
			)
			(layer "B.Fab")
		)
		(pad "1" smd circle
			(at 0.40005 0 180)
			(size 0 0)
			(layers "B.Cu" "B.Mask" "B.Paste")
			(net "P3V3_9ZXL045_P1_VDD")
		)
		(pad "2" smd circle
			(at -0.40005 0 180)
			(size 0 0)
			(layers "B.Cu" "B.Mask" "B.Paste")
			(net "GND")
		)
	)
	(footprint ""
		(layer "B.Cu")
		(at 238.633 -333.883 180)
		(property "Reference" "R801"
			(at 0 0 0)
			(layer "B.SilkS")
			(hide yes)
			(effects
				(font
					(size 1.27 1.27)
				)
				(justify mirror)
			)
		)
		(property "Value" ""
			(at 0 0 0)
			(layer "B.Fab")
			(effects
				(font
					(size 1.27 1.27)
				)
				(justify mirror)
			)
		)
		(duplicate_pad_numbers_are_jumpers no)
		(fp_line
			(start 0.32512 0.175006)
			(end 0.32512 -0.175006)
			(stroke
				(width 0.1)
				(type default)
			)
			(layer "B.Fab")
		)
		(fp_line
			(start 0.32512 -0.175006)
			(end -0.32512 -0.175006)
			(stroke
				(width 0.1)
				(type default)
			)
			(layer "B.Fab")
		)
		(fp_line
			(start -0.32512 0.175006)
			(end 0.32512 0.175006)
			(stroke
				(width 0.1)
				(type default)
			)
			(layer "B.Fab")
		)
		(fp_line
			(start -0.32512 -0.175006)
			(end -0.32512 0.175006)
			(stroke
				(width 0.1)
				(type default)
			)
			(layer "B.Fab")
		)
		(pad "1" smd rect
			(at 0.2667 0)
			(size 0.3048 0.381)
			(layers "B.Cu" "B.Mask" "B.Paste")
			(net "SMB_RT_CPU1_P0_ROM_MUX_2D_SDA")
		)
		(pad "2" smd rect
			(at -0.2667 0 180)
			(size 0.3048 0.381)
			(layers "B.Cu" "B.Mask" "B.Paste")
			(net "SMB_RT_CPU1_P0_ROM_MUX_2D_R_SDA")
		)
	)
	(footprint ""
		(layer "B.Cu")
		(at 317.702438 -199.998838)
		(property "Reference" "R6502"
			(at 0 0 0)
			(layer "B.SilkS")
			(hide yes)
			(effects
				(font
					(size 1.27 1.27)
				)
				(justify mirror)
			)
		)
		(property "Value" ""
			(at 0 0 0)
			(layer "B.Fab")
			(effects
				(font
					(size 1.27 1.27)
				)
				(justify mirror)
			)
		)
		(duplicate_pad_numbers_are_jumpers no)
		(fp_line
			(start -0.7874 -0.4064)
			(end -0.7874 0.4064)
			(stroke
				(width 0.1524)
				(type default)
			)
			(layer "B.SilkS")
		)
		(fp_line
			(start -0.7874 0.4064)
			(end 0.7874 0.4064)
			(stroke
				(width 0.1524)
				(type default)
			)
			(layer "B.SilkS")
		)
		(fp_line
			(start 0.7874 -0.4064)
			(end -0.7874 -0.4064)
			(stroke
				(width 0.1524)
				(type default)
			)
			(layer "B.SilkS")
		)
		(fp_line
			(start 0.7874 0.4064)
			(end 0.7874 -0.4064)
			(stroke
				(width 0.1524)
				(type default)
			)
			(layer "B.SilkS")
		)
		(fp_line
			(start -0.67945 -0.3048)
			(end -0.67945 0.3048)
			(stroke
				(width 0.1)
				(type default)
			)
			(layer "B.Fab")
		)
		(fp_line
			(start -0.67945 0.3048)
			(end -0.120396 0.3048)
			(stroke
				(width 0.1)
				(type default)
			)
			(layer "B.Fab")
		)
		(fp_line
			(start -0.12065 -0.3048)
			(end -0.67945 -0.3048)
			(stroke
				(width 0.1)
				(type default)
			)
			(layer "B.Fab")
		)
		(fp_line
			(start -0.12065 -0.2794)
			(end -0.12065 -0.3048)
			(stroke
				(width 0.1)
				(type default)
			)
			(layer "B.Fab")
		)
		(fp_line
			(start -0.120396 0.2794)
			(end 0.12065 0.2794)
			(stroke
				(width 0.1)
				(type default)
			)
			(layer "B.Fab")
		)
		(fp_line
			(start -0.120396 0.3048)
			(end -0.120396 0.2794)
			(stroke
				(width 0.1)
				(type default)
			)
			(layer "B.Fab")
		)
		(fp_line
			(start 0.12065 -0.305054)
			(end 0.12065 -0.2794)
			(stroke
				(width 0.1)
				(type default)
			)
			(layer "B.Fab")
		)
		(fp_line
			(start 0.12065 -0.2794)
			(end -0.12065 -0.2794)
			(stroke
				(width 0.1)
				(type default)
			)
			(layer "B.Fab")
		)
		(fp_line
			(start 0.12065 0.2794)
			(end 0.12065 0.3048)
			(stroke
				(width 0.1)
				(type default)
			)
			(layer "B.Fab")
		)
		(fp_line
			(start 0.12065 0.3048)
			(end 0.67945 0.3048)
			(stroke
				(width 0.1)
				(type default)
			)
			(layer "B.Fab")
		)
		(fp_line
			(start 0.67945 -0.305054)
			(end 0.12065 -0.305054)
			(stroke
				(width 0.1)
				(type default)
			)
			(layer "B.Fab")
		)
		(fp_line
			(start 0.67945 0.3048)
			(end 0.67945 -0.305054)
			(stroke
				(width 0.1)
				(type default)
			)
			(layer "B.Fab")
		)
		(pad "1" smd circle
			(at 0.40005 0 180)
			(size 0 0)
			(layers "B.Cu" "B.Mask" "B.Paste")
			(net "CPU0_FORCE_SELFREFRESH")
		)
		(pad "2" smd circle
			(at -0.40005 0 180)
			(size 0 0)
			(layers "B.Cu" "B.Mask" "B.Paste")
			(net "GND")
		)
	)
)
